# T6G (Grand Teton) — schematic netlist excerpt (pin names and nets, part order shuffled) for the footprints in the layout excerpt that follows; sources: Cadence DE-HDL packaged netlist, KiCad conversion of 04192023_DAF0TMB3IC0_F0TG_MB_C_brd_V02_OCP.brd

PU20  ISL99390FRZTR5935  ISL99390FRZ-TR5935 IC  pkg QFN21_6X5XB  page 206
  VOS  = PVDDIO_P0_VOS4
  AGND  = GND
  VCC  = PVDDIO_P0_VCC4
  PVCC  = PVDDCR_CPU1_P0_PVCC
  PGND1  = GND
  GL1  = NC_PVDDIO_P0_GL1_4
  PGND2  = GND
  SW  = SW_PVDDIO_P0_SW4
  VIN1  = SW_P12V_AUX_PVDDIO_P0_FLT
  VIN2  = SW_P12V_AUX_PVDDIO_P0_FLT
  DNC  = NC_PVDDIO_P0_DNC4
  PHASE  = SW_PVDDIO_P0_BOOTR4
  BOOT  = SW_PVDDIO_P0_BOOT4
  PWM  = PVDDIO_P0_PWM4
  EN  = PVDDIO_P0_VCC4
  TOUT_FLT  = PVDDIO_P0_TEMP1
  LSET  = PVDDIO_P0_LSET4
  IOUT  = PVDDIO_P0_IMON4
  REFIN  = PVDDCR_CPU1_P0_VCCS
  PGND3  = GND
  GL2  = NC_PVDDIO_P0_GL2_4

(kicad_pcb
	(version 20260206)
	(generator "pcbnew")
	(generator_version "10.0")
	(general
		(thickness 1.6)
		(legacy_teardrops no)
	)
	(paper "A4")
	(title_block
		(title "04192023_DAF0TMB3IC0_F0TG_MB_C_brd_V02_OCP.brd")
		(comment 1 "Grand Teton / footprints 2873-2873 of 8354")
	)
	(layers
		(0 "F.Cu" signal "TOP")
		(4 "In1.Cu" signal "GND")
		(6 "In2.Cu" signal "IN1")
		(8 "In3.Cu" signal "GND1")
		(10 "In4.Cu" signal "IN2")
		(12 "In5.Cu" signal "GND2")
		(14 "In6.Cu" signal "IN3")
		(16 "In7.Cu" signal "GND3")
		(18 "In8.Cu" signal "VCC")
		(20 "In9.Cu" signal "VCC1")
		(22 "In10.Cu" signal "GND4")
		(24 "In11.Cu" signal "IN4")
		(26 "In12.Cu" signal "GND5")
		(28 "In13.Cu" signal "IN5")
		(30 "In14.Cu" signal "GND6")
		(32 "In15.Cu" signal "IN6")
		(34 "In16.Cu" signal "GND7")
		(2 "B.Cu" signal "BOTTOM")
		(9 "F.Adhes" user "F.Adhesive")
		(11 "B.Adhes" user "B.Adhesive")
		(13 "F.Paste" user "Package Geometry/Pastemask Top")
		(15 "B.Paste" user "Package Geometry/Pastemask Bottom")
		(5 "F.SilkS" user "Ref Des/Silkscreen Top")
		(7 "B.SilkS" user "Ref Des/Silkscreen Bottom")
		(1 "F.Mask" user "Board Geometry/Soldermask Top")
		(3 "B.Mask" user "Board Geometry/Soldermask Bottom")
		(17 "Dwgs.User" user "User.Drawings")
		(19 "Cmts.User" user "User.Comments")
		(21 "Eco1.User" user "User.Eco1")
		(23 "Eco2.User" user "User.Eco2")
		(25 "Edge.Cuts" user "Board Geometry/Outline")
		(27 "Margin" user)
		(31 "F.CrtYd" user "Package Geometry/Place Bound Top")
		(29 "B.CrtYd" user "Package Geometry/Place Bound Bottom")
		(35 "F.Fab" user "Ref Des/Assembly Top")
		(33 "B.Fab" user "Ref Des/Assembly Bottom")
	)
	(footprint ""
		(layer "F.Cu")
		(at 275.422106 -346.71635)
		(property "Reference" "PU20"
			(at -1.737106 -7.58698 0)
			(unlocked yes)
			(layer "F.SilkS")
			(effects
				(font
					(size 0.7874 0.5842)
					(thickness 0.1524)
				)
				(justify left)
			)
		)
		(property "Value" ""
			(at 0 0 0)
			(layer "F.Fab")
			(effects
				(font
					(size 1.27 1.27)
				)
			)
		)
		(duplicate_pad_numbers_are_jumpers no)
		(fp_line
			(start -2.500122 -2.999994)
			(end -2.24409 -2.999994)
			(stroke
				(width 0.1524)
				(type default)
			)
			(layer "F.SilkS")
		)
		(fp_line
			(start -2.500122 -2.529078)
			(end -2.500122 -2.999994)
			(stroke
				(width 0.1524)
				(type default)
			)
			(layer "F.SilkS")
		)
		(fp_line
			(start -2.500122 0.6604)
			(end -2.500122 0.229108)
			(stroke
				(width 0.1524)
				(type default)
			)
			(layer "F.SilkS")
		)
		(fp_line
			(start -2.500122 2.999994)
			(end -2.500122 2.339594)
			(stroke
				(width 0.1524)
				(type default)
			)
			(layer "F.SilkS")
		)
		(fp_line
			(start -2.2987 2.999994)
			(end -2.500122 2.999994)
			(stroke
				(width 0.1524)
				(type default)
			)
			(layer "F.SilkS")
		)
		(fp_line
			(start 2.31394 -2.999994)
			(end 2.500122 -2.999994)
			(stroke
				(width 0.1524)
				(type default)
			)
			(layer "F.SilkS")
		)
		(fp_line
			(start 2.500122 -2.999994)
			(end 2.500122 -2.44348)
			(stroke
				(width 0.1524)
				(type default)
			)
			(layer "F.SilkS")
		)
		(fp_line
			(start 2.500122 2.339594)
			(end 2.500122 2.999994)
			(stroke
				(width 0.1524)
				(type default)
			)
			(layer "F.SilkS")
		)
		(fp_line
			(start 2.500122 2.999994)
			(end 2.2987 2.999994)
			(stroke
				(width 0.1524)
				(type default)
			)
			(layer "F.SilkS")
		)
		(fp_poly
			(pts
				(xy -3.464814 -2.702052) (xy -2.983484 -3.183382) (xy -2.742946 -2.461514)
			)
			(stroke
				(width 0)
				(type default)
			)
			(fill yes)
			(layer "F.SilkS")
		)
		(fp_line
			(start -2.500122 -2.999994)
			(end 2.500122 -2.999994)
			(stroke
				(width 0.1)
				(type default)
			)
			(layer "F.Fab")
		)
		(fp_line
			(start -2.500122 2.999994)
			(end -2.500122 -2.999994)
			(stroke
				(width 0.1)
				(type default)
			)
			(layer "F.Fab")
		)
		(fp_line
			(start 2.500122 -2.999994)
			(end 2.500122 2.999994)
			(stroke
				(width 0.1)
				(type default)
			)
			(layer "F.Fab")
		)
		(fp_line
			(start 2.500122 2.999994)
			(end -2.500122 2.999994)
			(stroke
				(width 0.1)
				(type default)
			)
			(layer "F.Fab")
		)
		(fp_poly
			(pts
				(xy -4.218432 -2.783078) (xy -4.218432 -1.767078) (xy -3.202432 -2.275078)
			)
			(stroke
				(width 0)
				(type default)
			)
			(fill yes)
			(layer "F.Fab")
		)
		(pad "1" smd rect
			(at -2.400046 -2.275078 90)
			(size 0.2286 0.6096)
			(layers "F.Cu" "F.Mask" "F.Paste")
			(net "PVDDIO_P0_VOS4")
		)
		(pad "2" smd rect
			(at -2.400046 -1.82499 90)
			(size 0.2286 0.6096)
			(layers "F.Cu" "F.Mask" "F.Paste")
			(net "GND")
		)
		(pad "3" smd rect
			(at -2.400046 -1.374902 90)
			(size 0.2286 0.6096)
			(layers "F.Cu" "F.Mask" "F.Paste")
			(net "PVDDIO_P0_VCC4")
		)
		(pad "4" smd rect
			(at -2.400046 -0.925068 90)
			(size 0.2286 0.6096)
			(layers "F.Cu" "F.Mask" "F.Paste")
			(net "PVDDCR_CPU1_P0_PVCC")
		)
		(pad "5" smd rect
			(at -2.400046 -0.47498 90)
			(size 0.2286 0.6096)
			(layers "F.Cu" "F.Mask" "F.Paste")
			(net "GND")
		)
		(pad "6" smd rect
			(at -2.400046 -0.024892 90)
			(size 0.2286 0.6096)
			(layers "F.Cu" "F.Mask" "F.Paste")
			(net "NC_PVDDIO_P0_GL1_4")
		)
		(pad "7_9-20_24" smd circle
			(at 0 1.150112 90)
			(size 0 0)
			(layers "F.Cu" "F.Mask" "F.Paste")
			(net "GND")
		)
		(pad "10_19" smd rect
			(at 0 2.899918 90)
			(size 0.6096 4.318)
			(layers "F.Cu" "F.Mask" "F.Paste")
			(net "SW_PVDDIO_P0_SW4")
		)
		(pad "25_29" smd rect
			(at 1.549908 -1.279906 270)
			(size 2.0574 2.3114)
			(layers "F.Cu" "F.Mask" "F.Paste")
			(net "SW_P12V_AUX_PVDDIO_P0_FLT")
		)
		(pad "30" smd rect
			(at 2.05994 -2.899918)
			(size 0.2286 0.6096)
			(layers "F.Cu" "F.Mask" "F.Paste")
			(net "SW_P12V_AUX_PVDDIO_P0_FLT")
		)
		(pad "31" smd rect
			(at 1.610106 -2.899918)
			(size 0.2286 0.6096)
			(layers "F.Cu" "F.Mask" "F.Paste")
			(net "NC_PVDDIO_P0_DNC4")
		)
		(pad "32" smd rect
			(at 1.160018 -2.899918)
			(size 0.2286 0.6096)
			(layers "F.Cu" "F.Mask" "F.Paste")
			(net "SW_PVDDIO_P0_BOOTR4")
		)
		(pad "33" smd rect
			(at 0.70993 -2.899918)
			(size 0.2286 0.6096)
			(layers "F.Cu" "F.Mask" "F.Paste")
			(net "SW_PVDDIO_P0_BOOT4")
		)
		(pad "34" smd rect
			(at 0.260096 -2.899918)
			(size 0.2286 0.6096)
			(layers "F.Cu" "F.Mask" "F.Paste")
			(net "PVDDIO_P0_PWM4")
		)
		(pad "35" smd rect
			(at -0.189992 -2.899918)
			(size 0.2286 0.6096)
			(layers "F.Cu" "F.Mask" "F.Paste")
			(net "PVDDIO_P0_VCC4")
		)
		(pad "36" smd rect
			(at -0.64008 -2.899918)
			(size 0.2286 0.6096)
			(layers "F.Cu" "F.Mask" "F.Paste")
			(net "PVDDIO_P0_TEMP1")
		)
		(pad "37" smd rect
			(at -1.089914 -2.899918)
			(size 0.2286 0.6096)
			(layers "F.Cu" "F.Mask" "F.Paste")
			(net "PVDDIO_P0_LSET4")
		)
		(pad "38" smd rect
			(at -1.540002 -2.899918)
			(size 0.2286 0.6096)
			(layers "F.Cu" "F.Mask" "F.Paste")
			(net "PVDDIO_P0_IMON4")
		)
		(pad "39" smd rect
			(at -1.99009 -2.899918)
			(size 0.2286 0.6096)
			(layers "F.Cu" "F.Mask" "F.Paste")
			(net "PVDDCR_CPU1_P0_VCCS")
		)
		(pad "40" smd rect
			(at -0.87503 -1.27508)
			(size 1.7526 1.9558)
			(layers "F.Cu" "F.Mask" "F.Paste")
			(net "GND")
		)
		(pad "41" smd rect
			(at -1.525016 0.249936 270)
			(size 0.3048 0.4572)
			(layers "F.Cu" "F.Mask" "F.Paste")
			(net "NC_PVDDIO_P0_GL2_4")
		)
		(zone
			(layer "F.Cu")
			(hatch none 0.5)
			(connect_pads
				(clearance 0)
			)
			(min_thickness 0.25)
			(keepout
				(tracks not_allowed)
				(vias allowed)
				(pads allowed)
				(copperpour not_allowed)
				(footprints allowed)
			)
			(placement
				(enabled no)
				(sheetname "")
			)
			(fill
				(thermal_gap 0.5)
				(thermal_bridge_width 0.5)
				(island_removal_mode 0)
			)
			(polygon
				(pts
					(xy 272.921984 -344.138758) (xy 272.921984 -344.465656) (xy 277.922228 -344.465656) (xy 277.922228 -344.141806)
					(xy 277.631906 -344.141806) (xy 277.631906 -344.172032) (xy 273.212306 -344.172032) (xy 273.212306 -344.138758)
				)
			)
		)
		(zone
			(layer "F.Cu")
			(hatch none 0.5)
			(connect_pads
				(clearance 0)
			)
			(min_thickness 0.25)
			(keepout
				(tracks not_allowed)
				(vias allowed)
				(pads allowed)
				(copperpour not_allowed)
				(footprints allowed)
			)
			(placement
				(enabled no)
				(sheetname "")
			)
			(fill
				(thermal_gap 0.5)
				(thermal_bridge_width 0.5)
				(island_removal_mode 0)
			)
			(polygon
				(pts
					(xy 275.474176 -346.96273) (xy 275.474176 -349.02013) (xy 273.619976 -349.02013) (xy 273.619976 -348.779084)
					(xy 273.37766 -348.779084) (xy 273.37766 -349.260668) (xy 277.21814 -349.260668) (xy 277.21814 -349.075756)
					(xy 275.765514 -349.075756) (xy 275.765514 -346.916756) (xy 277.922228 -346.916756) (xy 277.922228 -346.667074)
					(xy 275.769832 -346.667074)
				)
			)
		)
	)
)
